# S9S_MB_2U (Grand Teton) — schematic netlist excerpt (pin names and nets, part order shuffled) for the footprints in the layout excerpt that follows; sources: Cadence DE-HDL packaged netlist, KiCad conversion of 03242023_DA0F0TMBIJ0_F0T_Motherboard_J_brd_V01_OCP.brd

C242  Q_CAP  10UF 6.3V 20% X6S  pkg C0402  page 77 : A = PVCCIN_CPU1 ; B = GND
R1643  Q_RES  100K 1% CHIP  pkg 0402LF  page 260 : A = P12V_AUX ; B = VR_P5V_EN_N

(kicad_pcb
	(version 20260206)
	(generator "pcbnew")
	(generator_version "10.0")
	(general
		(thickness 1.6)
		(legacy_teardrops no)
	)
	(paper "A4")
	(title_block
		(title "03242023_DA0F0TMBIJ0_F0T_Motherboard_J_brd_V01_OCP.brd")
		(comment 1 "Grand Teton / footprints 1237-1238 of 6105")
	)
	(layers
		(0 "F.Cu" signal "TOP")
		(4 "In1.Cu" signal "GND")
		(6 "In2.Cu" signal "IN1")
		(8 "In3.Cu" signal "GND1")
		(10 "In4.Cu" signal "IN2")
		(12 "In5.Cu" signal "GND2")
		(14 "In6.Cu" signal "IN3")
		(16 "In7.Cu" signal "GND3")
		(18 "In8.Cu" signal "VCC")
		(20 "In9.Cu" signal "VCC1")
		(22 "In10.Cu" signal "GND4")
		(24 "In11.Cu" signal "IN4")
		(26 "In12.Cu" signal "GND5")
		(28 "In13.Cu" signal "IN5")
		(30 "In14.Cu" signal "GND6")
		(32 "In15.Cu" signal "IN6")
		(34 "In16.Cu" signal "GND7")
		(2 "B.Cu" signal "BOTTOM")
		(9 "F.Adhes" user "F.Adhesive")
		(11 "B.Adhes" user "B.Adhesive")
		(13 "F.Paste" user "Package Geometry/Pastemask Top")
		(15 "B.Paste" user "Package Geometry/Pastemask Bottom")
		(5 "F.SilkS" user "Ref Des/Silkscreen Top")
		(7 "B.SilkS" user "Ref Des/Silkscreen Bottom")
		(1 "F.Mask" user "Board Geometry/Soldermask Top")
		(3 "B.Mask" user "Board Geometry/Soldermask Bottom")
		(17 "Dwgs.User" user "User.Drawings")
		(19 "Cmts.User" user "User.Comments")
		(21 "Eco1.User" user "User.Eco1")
		(23 "Eco2.User" user "User.Eco2")
		(25 "Edge.Cuts" user "Board Geometry/Outline")
		(27 "Margin" user)
		(31 "F.CrtYd" user "Package Geometry/Place Bound Top")
		(29 "B.CrtYd" user "Package Geometry/Place Bound Bottom")
		(35 "F.Fab" user "Ref Des/Assembly Top")
		(33 "B.Fab" user "Ref Des/Assembly Bottom")
	)
	(footprint ""
		(layer "F.Cu")
		(at 164.29101 -130.526536 -90)
		(property "Reference" "R1643"
			(at 0 0 270)
			(layer "F.SilkS")
			(hide yes)
			(effects
				(font
					(size 1.27 1.27)
				)
			)
		)
		(property "Value" ""
			(at 0 0 270)
			(layer "F.Fab")
			(effects
				(font
					(size 1.27 1.27)
				)
			)
		)
		(duplicate_pad_numbers_are_jumpers no)
		(fp_line
			(start -0.7874 0.4064)
			(end -0.7874 -0.4064)
			(stroke
				(width 0.1524)
				(type default)
			)
			(layer "F.SilkS")
		)
		(fp_line
			(start 0.7874 0.4064)
			(end -0.7874 0.4064)
			(stroke
				(width 0.1524)
				(type default)
			)
			(layer "F.SilkS")
		)
		(fp_line
			(start -0.7874 -0.4064)
			(end 0.7874 -0.4064)
			(stroke
				(width 0.1524)
				(type default)
			)
			(layer "F.SilkS")
		)
		(fp_line
			(start 0.7874 -0.4064)
			(end 0.7874 0.4064)
			(stroke
				(width 0.1524)
				(type default)
			)
			(layer "F.SilkS")
		)
		(fp_line
			(start -0.67945 0.3048)
			(end -0.67945 -0.305054)
			(stroke
				(width 0.1)
				(type default)
			)
			(layer "F.Fab")
		)
		(fp_line
			(start -0.12065 0.3048)
			(end -0.67945 0.3048)
			(stroke
				(width 0.1)
				(type default)
			)
			(layer "F.Fab")
		)
		(fp_line
			(start 0.120396 0.3048)
			(end 0.120396 0.2794)
			(stroke
				(width 0.1)
				(type default)
			)
			(layer "F.Fab")
		)
		(fp_line
			(start 0.67945 0.3048)
			(end 0.120396 0.3048)
			(stroke
				(width 0.1)
				(type default)
			)
			(layer "F.Fab")
		)
		(fp_line
			(start -0.12065 0.2794)
			(end -0.12065 0.3048)
			(stroke
				(width 0.1)
				(type default)
			)
			(layer "F.Fab")
		)
		(fp_line
			(start 0.120396 0.2794)
			(end -0.12065 0.2794)
			(stroke
				(width 0.1)
				(type default)
			)
			(layer "F.Fab")
		)
		(fp_line
			(start -0.12065 -0.2794)
			(end 0.12065 -0.2794)
			(stroke
				(width 0.1)
				(type default)
			)
			(layer "F.Fab")
		)
		(fp_line
			(start 0.12065 -0.2794)
			(end 0.12065 -0.3048)
			(stroke
				(width 0.1)
				(type default)
			)
			(layer "F.Fab")
		)
		(fp_line
			(start 0.12065 -0.3048)
			(end 0.67945 -0.3048)
			(stroke
				(width 0.1)
				(type default)
			)
			(layer "F.Fab")
		)
		(fp_line
			(start 0.67945 -0.3048)
			(end 0.67945 0.3048)
			(stroke
				(width 0.1)
				(type default)
			)
			(layer "F.Fab")
		)
		(fp_line
			(start -0.67945 -0.305054)
			(end -0.12065 -0.305054)
			(stroke
				(width 0.1)
				(type default)
			)
			(layer "F.Fab")
		)
		(fp_line
			(start -0.12065 -0.305054)
			(end -0.12065 -0.2794)
			(stroke
				(width 0.1)
				(type default)
			)
			(layer "F.Fab")
		)
		(pad "1" smd circle
			(at -0.40005 0 270)
			(size 0 0)
			(layers "F.Cu" "F.Mask" "F.Paste")
			(net "P12V_AUX")
		)
		(pad "2" smd circle
			(at 0.40005 0 270)
			(size 0 0)
			(layers "F.Cu" "F.Mask" "F.Paste")
			(net "VR_P5V_EN_N")
		)
	)
	(footprint ""
		(layer "F.Cu")
		(at 105.30713 -241.97691 -90)
		(property "Reference" "C242"
			(at 0 0 270)
			(layer "F.SilkS")
			(hide yes)
			(effects
				(font
					(size 1.27 1.27)
				)
			)
		)
		(property "Value" ""
			(at 0 0 270)
			(layer "F.Fab")
			(effects
				(font
					(size 1.27 1.27)
				)
			)
		)
		(duplicate_pad_numbers_are_jumpers no)
		(fp_line
			(start -0.7874 0.4064)
			(end -0.7874 -0.4064)
			(stroke
				(width 0.1524)
				(type default)
			)
			(layer "F.SilkS")
		)
		(fp_line
			(start 0.7874 0.4064)
			(end -0.7874 0.4064)
			(stroke
				(width 0.1524)
				(type default)
			)
			(layer "F.SilkS")
		)
		(fp_line
			(start -0.7874 -0.4064)
			(end 0.7874 -0.4064)
			(stroke
				(width 0.1524)
				(type default)
			)
			(layer "F.SilkS")
		)
		(fp_line
			(start 0.7874 -0.4064)
			(end 0.7874 0.4064)
			(stroke
				(width 0.1524)
				(type default)
			)
			(layer "F.SilkS")
		)
		(fp_line
			(start -0.67945 0.3048)
			(end -0.67945 -0.305054)
			(stroke
				(width 0.1)
				(type default)
			)
			(layer "F.Fab")
		)
		(fp_line
			(start -0.12065 0.3048)
			(end -0.67945 0.3048)
			(stroke
				(width 0.1)
				(type default)
			)
			(layer "F.Fab")
		)
		(fp_line
			(start 0.120396 0.3048)
			(end 0.120396 0.2794)
			(stroke
				(width 0.1)
				(type default)
			)
			(layer "F.Fab")
		)
		(fp_line
			(start 0.67945 0.3048)
			(end 0.120396 0.3048)
			(stroke
				(width 0.1)
				(type default)
			)
			(layer "F.Fab")
		)
		(fp_line
			(start -0.12065 0.2794)
			(end -0.12065 0.3048)
			(stroke
				(width 0.1)
				(type default)
			)
			(layer "F.Fab")
		)
		(fp_line
			(start 0.120396 0.2794)
			(end -0.12065 0.2794)
			(stroke
				(width 0.1)
				(type default)
			)
			(layer "F.Fab")
		)
		(fp_line
			(start -0.12065 -0.2794)
			(end 0.12065 -0.2794)
			(stroke
				(width 0.1)
				(type default)
			)
			(layer "F.Fab")
		)
		(fp_line
			(start 0.12065 -0.2794)
			(end 0.12065 -0.3048)
			(stroke
				(width 0.1)
				(type default)
			)
			(layer "F.Fab")
		)
		(fp_line
			(start 0.12065 -0.3048)
			(end 0.67945 -0.3048)
			(stroke
				(width 0.1)
				(type default)
			)
			(layer "F.Fab")
		)
		(fp_line
			(start 0.67945 -0.3048)
			(end 0.67945 0.3048)
			(stroke
				(width 0.1)
				(type default)
			)
			(layer "F.Fab")
		)
		(fp_line
			(start -0.67945 -0.305054)
			(end -0.12065 -0.305054)
			(stroke
				(width 0.1)
				(type default)
			)
			(layer "F.Fab")
		)
		(fp_line
			(start -0.12065 -0.305054)
			(end -0.12065 -0.2794)
			(stroke
				(width 0.1)
				(type default)
			)
			(layer "F.Fab")
		)
		(pad "1" smd circle
			(at -0.40005 0 270)
			(size 0 0)
			(layers "F.Cu" "F.Mask" "F.Paste")
			(net "PVCCIN_CPU1")
		)
		(pad "2" smd circle
			(at 0.40005 0 270)
			(size 0 0)
			(layers "F.Cu" "F.Mask" "F.Paste")
			(net "GND")
		)
	)
)
